# SCM (Grand Teton) — schematic netlist excerpt (pin names and nets, part order shuffled) for the footprints in the layout excerpt that follows; sources: Cadence DE-HDL packaged netlist, KiCad conversion of 12092022_DA0F0TMDCD0_F0T_Management_Board_D_brd_V3_OCP.brd

C11  Q_CAP  0.1UF 25V 10% X7R  pkg 0402  page 31 : A = P3V3_AUX ; B = GND
R740  Q_RES  4.7K 1% CHIP  pkg 0402LF  page 28 : A = P3V3_AUX ; B = LED_POSTCODE_A2

(kicad_pcb
	(version 20260206)
	(generator "pcbnew")
	(generator_version "10.0")
	(general
		(thickness 1.6)
		(legacy_teardrops no)
	)
	(paper "A4")
	(title_block
		(title "12092022_DA0F0TMDCD0_F0T_Management_Board_D_brd_V3_OCP.brd")
		(comment 1 "Grand Teton / footprints 866-867 of 1440")
	)
	(layers
		(0 "F.Cu" signal "TOP")
		(4 "In1.Cu" signal "GND")
		(6 "In2.Cu" signal "IN1")
		(8 "In3.Cu" signal "GND1")
		(10 "In4.Cu" signal "IN2")
		(12 "In5.Cu" signal "VCC")
		(14 "In6.Cu" signal "VCC1")
		(16 "In7.Cu" signal "IN3")
		(18 "In8.Cu" signal "GND2")
		(20 "In9.Cu" signal "IN4")
		(22 "In10.Cu" signal "GND3")
		(2 "B.Cu" signal "BOTTOM")
		(9 "F.Adhes" user "F.Adhesive")
		(11 "B.Adhes" user "B.Adhesive")
		(13 "F.Paste" user "Package Geometry/Pastemask Top")
		(15 "B.Paste" user "Package Geometry/Pastemask Bottom")
		(5 "F.SilkS" user "Ref Des/Silkscreen Top")
		(7 "B.SilkS" user "Ref Des/Silkscreen Bottom")
		(1 "F.Mask" user "Board Geometry/Soldermask Top")
		(3 "B.Mask" user "Board Geometry/Soldermask Bottom")
		(17 "Dwgs.User" user "User.Drawings")
		(19 "Cmts.User" user "User.Comments")
		(21 "Eco1.User" user "User.Eco1")
		(23 "Eco2.User" user "User.Eco2")
		(25 "Edge.Cuts" user "Board Geometry/Outline")
		(27 "Margin" user)
		(31 "F.CrtYd" user "Package Geometry/Place Bound Top")
		(29 "B.CrtYd" user "Package Geometry/Place Bound Bottom")
		(35 "F.Fab" user "Ref Des/Assembly Top")
		(33 "B.Fab" user "Ref Des/Assembly Bottom")
	)
	(footprint ""
		(layer "B.Cu")
		(at 31.496 -70.358 180)
		(property "Reference" "C11"
			(at 0 0 0)
			(layer "B.SilkS")
			(hide yes)
			(effects
				(font
					(size 1.27 1.27)
				)
				(justify mirror)
			)
		)
		(property "Value" ""
			(at 0 0 0)
			(layer "B.Fab")
			(effects
				(font
					(size 1.27 1.27)
				)
				(justify mirror)
			)
		)
		(duplicate_pad_numbers_are_jumpers no)
		(fp_line
			(start 0.7874 0.4064)
			(end 0.7874 -0.4064)
			(stroke
				(width 0.1524)
				(type default)
			)
			(layer "B.SilkS")
		)
		(fp_line
			(start 0.7874 -0.4064)
			(end -0.7874 -0.4064)
			(stroke
				(width 0.1524)
				(type default)
			)
			(layer "B.SilkS")
		)
		(fp_line
			(start -0.7874 0.4064)
			(end 0.7874 0.4064)
			(stroke
				(width 0.1524)
				(type default)
			)
			(layer "B.SilkS")
		)
		(fp_line
			(start -0.7874 -0.4064)
			(end -0.7874 0.4064)
			(stroke
				(width 0.1524)
				(type default)
			)
			(layer "B.SilkS")
		)
		(fp_line
			(start 0.67945 0.3048)
			(end 0.67945 -0.305054)
			(stroke
				(width 0.1)
				(type default)
			)
			(layer "B.Fab")
		)
		(fp_line
			(start 0.67945 -0.305054)
			(end 0.12065 -0.305054)
			(stroke
				(width 0.1)
				(type default)
			)
			(layer "B.Fab")
		)
		(fp_line
			(start 0.12065 0.3048)
			(end 0.67945 0.3048)
			(stroke
				(width 0.1)
				(type default)
			)
			(layer "B.Fab")
		)
		(fp_line
			(start 0.12065 0.2794)
			(end 0.12065 0.3048)
			(stroke
				(width 0.1)
				(type default)
			)
			(layer "B.Fab")
		)
		(fp_line
			(start 0.12065 -0.2794)
			(end -0.12065 -0.2794)
			(stroke
				(width 0.1)
				(type default)
			)
			(layer "B.Fab")
		)
		(fp_line
			(start 0.12065 -0.305054)
			(end 0.12065 -0.2794)
			(stroke
				(width 0.1)
				(type default)
			)
			(layer "B.Fab")
		)
		(fp_line
			(start -0.120396 0.3048)
			(end -0.120396 0.2794)
			(stroke
				(width 0.1)
				(type default)
			)
			(layer "B.Fab")
		)
		(fp_line
			(start -0.120396 0.2794)
			(end 0.12065 0.2794)
			(stroke
				(width 0.1)
				(type default)
			)
			(layer "B.Fab")
		)
		(fp_line
			(start -0.12065 -0.2794)
			(end -0.12065 -0.3048)
			(stroke
				(width 0.1)
				(type default)
			)
			(layer "B.Fab")
		)
		(fp_line
			(start -0.12065 -0.3048)
			(end -0.67945 -0.3048)
			(stroke
				(width 0.1)
				(type default)
			)
			(layer "B.Fab")
		)
		(fp_line
			(start -0.67945 0.3048)
			(end -0.120396 0.3048)
			(stroke
				(width 0.1)
				(type default)
			)
			(layer "B.Fab")
		)
		(fp_line
			(start -0.67945 -0.3048)
			(end -0.67945 0.3048)
			(stroke
				(width 0.1)
				(type default)
			)
			(layer "B.Fab")
		)
		(pad "1" smd circle
			(at 0.40005 0)
			(size 0 0)
			(layers "B.Cu" "B.Mask" "B.Paste")
			(net "P3V3_AUX")
		)
		(pad "2" smd circle
			(at -0.40005 0)
			(size 0 0)
			(layers "B.Cu" "B.Mask" "B.Paste")
			(net "GND")
		)
	)
	(footprint ""
		(layer "B.Cu")
		(at 63.9572 -90.2208)
		(property "Reference" "R740"
			(at 0 0 0)
			(layer "B.SilkS")
			(hide yes)
			(effects
				(font
					(size 1.27 1.27)
				)
				(justify mirror)
			)
		)
		(property "Value" ""
			(at 0 0 0)
			(layer "B.Fab")
			(effects
				(font
					(size 1.27 1.27)
				)
				(justify mirror)
			)
		)
		(duplicate_pad_numbers_are_jumpers no)
		(fp_line
			(start -0.7874 -0.4064)
			(end -0.7874 0.4064)
			(stroke
				(width 0.1524)
				(type default)
			)
			(layer "B.SilkS")
		)
		(fp_line
			(start -0.7874 0.4064)
			(end 0.7874 0.4064)
			(stroke
				(width 0.1524)
				(type default)
			)
			(layer "B.SilkS")
		)
		(fp_line
			(start 0.7874 -0.4064)
			(end -0.7874 -0.4064)
			(stroke
				(width 0.1524)
				(type default)
			)
			(layer "B.SilkS")
		)
		(fp_line
			(start 0.7874 0.4064)
			(end 0.7874 -0.4064)
			(stroke
				(width 0.1524)
				(type default)
			)
			(layer "B.SilkS")
		)
		(fp_line
			(start -0.67945 -0.3048)
			(end -0.67945 0.3048)
			(stroke
				(width 0.1)
				(type default)
			)
			(layer "B.Fab")
		)
		(fp_line
			(start -0.67945 0.3048)
			(end -0.120396 0.3048)
			(stroke
				(width 0.1)
				(type default)
			)
			(layer "B.Fab")
		)
		(fp_line
			(start -0.12065 -0.3048)
			(end -0.67945 -0.3048)
			(stroke
				(width 0.1)
				(type default)
			)
			(layer "B.Fab")
		)
		(fp_line
			(start -0.12065 -0.2794)
			(end -0.12065 -0.3048)
			(stroke
				(width 0.1)
				(type default)
			)
			(layer "B.Fab")
		)
		(fp_line
			(start -0.120396 0.2794)
			(end 0.12065 0.2794)
			(stroke
				(width 0.1)
				(type default)
			)
			(layer "B.Fab")
		)
		(fp_line
			(start -0.120396 0.3048)
			(end -0.120396 0.2794)
			(stroke
				(width 0.1)
				(type default)
			)
			(layer "B.Fab")
		)
		(fp_line
			(start 0.12065 -0.305054)
			(end 0.12065 -0.2794)
			(stroke
				(width 0.1)
				(type default)
			)
			(layer "B.Fab")
		)
		(fp_line
			(start 0.12065 -0.2794)
			(end -0.12065 -0.2794)
			(stroke
				(width 0.1)
				(type default)
			)
			(layer "B.Fab")
		)
		(fp_line
			(start 0.12065 0.2794)
			(end 0.12065 0.3048)
			(stroke
				(width 0.1)
				(type default)
			)
			(layer "B.Fab")
		)
		(fp_line
			(start 0.12065 0.3048)
			(end 0.67945 0.3048)
			(stroke
				(width 0.1)
				(type default)
			)
			(layer "B.Fab")
		)
		(fp_line
			(start 0.67945 -0.305054)
			(end 0.12065 -0.305054)
			(stroke
				(width 0.1)
				(type default)
			)
			(layer "B.Fab")
		)
		(fp_line
			(start 0.67945 0.3048)
			(end 0.67945 -0.305054)
			(stroke
				(width 0.1)
				(type default)
			)
			(layer "B.Fab")
		)
		(pad "1" smd circle
			(at 0.40005 0 180)
			(size 0 0)
			(layers "B.Cu" "B.Mask" "B.Paste")
			(net "P3V3_AUX")
		)
		(pad "2" smd circle
			(at -0.40005 0 180)
			(size 0 0)
			(layers "B.Cu" "B.Mask" "B.Paste")
			(net "LED_POSTCODE_A2")
		)
	)
)
